G04 ================== begin FILE IDENTIFICATION RECORD ==================*
G04 Layout Name:  9052_F0T_PDB_Converter_Brick_F_V03_1208_1600.brd*
G04 Film Name:    pmb*
G04 File Format:  Gerber RS274X*
G04 File Origin:  Cadence Allegro 17.2-S081*
G04 Origin Date:  Wed Dec 21 09:54:59 2022*
G04 *
G04 Layer:  DRAWING FORMAT/TITLE_BLOCK_A*
G04 Layer:  VIA CLASS/PASTEMASK_BOTTOM*
G04 Layer:  PIN/PASTEMASK_BOTTOM*
G04 Layer:  PACKAGE GEOMETRY/PASTEMASK_BOTTOM*
G04 Layer:  MANUFACTURING/PHOTOPLOT_OUTLINE*
G04 Layer:  DRAWING FORMAT/TITLE_BLOCK*
G04 Layer:  DRAWING FORMAT/TITLE_DATA_PMB*
G04 *
G04 Offset:    (0.00 0.00)*
G04 Mirror:    No*
G04 Mode:      Positive*
G04 Rotation:  0*
G04 FullContactRelief:  No*
G04 UndefLineWidth:     6.00*
G04 ================== end FILE IDENTIFICATION RECORD ====================*
%FSLAX25Y25*MOIN*%
%IR0*IPPOS*OFA0.00000B0.00000*MIA0B0*SFA1.00000B1.00000*%
%AMMACRO18*
4,1,8,.02953,-.06299,
-.02953,-.06299,
-.02953,.06299,
.02953,.06299,
.02953,.01968,
-.01771,.01968,
-.01771,-.01968,
.02953,-.01968,
.02953,-.06299,
0.0*
%
%ADD18MACRO18*%
%ADD54R,.13X.095*%
%ADD11C,.05*%
%ADD32C,.06*%
%ADD26C,.052*%
%ADD24C,.062*%
%ADD13C,.026*%
%ADD45C,.066*%
%ADD29C,.093*%
%ADD25C,.039*%
%ADD12R,.05X.05*%
%ADD33R,.06X.06*%
%ADD10C,.058*%
%ADD23R,.062X.062*%
%ADD44R,.066X.066*%
%ADD35R,.093X.093*%
%AMMACRO31*
4,1,28,-.00748,.00052,
-.00984,.00052,
-.00984,.00603,
-.009782,.006705,
-.009607,.007359,
-.009321,.007974,
-.008933,.008529,
-.008455,.009009,
-.0079,.009398,
-.007286,.009685,
-.006632,.009861,
-.005957,.00992,
-.00591,.00992,
.00591,.00992,
.006585,.009869,
.007242,.009701,
.007859,.009421,
.008418,.009039,
.008903,.008565,
.009297,.008015,
.009591,.007404,
.009773,.006751,
.00984,.006077,
.00984,.00603,
.00984,.00052,
.00748,.00052,
.00748,-.00991,
-.00748,-.00991,
-.00748,.00052,
0.0*
%
%ADD31MACRO31*%
%AMMACRO16*
4,1,28,.00052,.00748,
.00052,.00984,
.00603,.00984,
.006705,.009782,
.007359,.009607,
.007974,.009321,
.008529,.008933,
.009009,.008455,
.009398,.0079,
.009685,.007286,
.009861,.006632,
.00992,.005957,
.00992,.00591,
.00992,-.00591,
.009869,-.006585,
.009701,-.007242,
.009421,-.007859,
.009039,-.008418,
.008565,-.008903,
.008015,-.009297,
.007404,-.009591,
.006751,-.009773,
.006077,-.00984,
.00603,-.00984,
.00052,-.00984,
.00052,-.00748,
-.00991,-.00748,
-.00991,.00748,
.00052,.00748,
0.0*
%
%ADD16MACRO16*%
%AMMACRO30*
4,1,28,-.00748,-.00051,
-.00984,-.00051,
-.00984,-.00602,
-.009782,-.006695,
-.009607,-.007349,
-.009321,-.007964,
-.008933,-.008519,
-.008455,-.008998,
-.0079,-.009388,
-.007287,-.009675,
-.006632,-.009851,
-.005958,-.00991,
-.00591,-.00991,
.00591,-.00991,
.006585,-.009859,
.007242,-.009691,
.007859,-.009411,
.008418,-.009029,
.008903,-.008555,
.009297,-.008005,
.00959,-.007394,
.009773,-.006742,
.00984,-.006068,
.00984,-.00602,
.00984,-.00051,
.00748,-.00051,
.00748,.00992,
-.00748,.00992,
-.00748,-.00051,
0.0*
%
%ADD30MACRO30*%
%AMMACRO15*
4,1,28,-.00051,.00748,
-.00051,.00984,
-.00602,.00984,
-.006695,.009782,
-.007349,.009607,
-.007964,.009321,
-.008519,.008933,
-.008998,.008455,
-.009388,.0079,
-.009675,.007287,
-.009851,.006632,
-.00991,.005958,
-.00991,.00591,
-.00991,-.00591,
-.009859,-.006585,
-.009691,-.007242,
-.009411,-.007859,
-.009029,-.008418,
-.008555,-.008903,
-.008005,-.009297,
-.007394,-.00959,
-.006742,-.009773,
-.006068,-.00984,
-.00602,-.00984,
-.00051,-.00984,
-.00051,-.00748,
.00992,-.00748,
.00992,.00748,
-.00051,.00748,
0.0*
%
%ADD15MACRO15*%
%ADD14R,.05X.04*%
%ADD34R,.02X.018*%
%ADD52R,.018X.02*%
%ADD51R,.034X.032*%
%AMMACRO19*
4,1,8,-.02953,.06299,
.02953,.06299,
.02953,-.06299,
-.02953,-.06299,
-.02953,-.01968,
.01771,-.01968,
.01771,.01968,
-.02953,.01968,
-.02953,.06299,
0.0*
%
%ADD19MACRO19*%
%ADD36R,.036X.032*%
%ADD50R,.032X.028*%
%ADD48R,.032X.036*%
%ADD39R,.017X.024*%
%ADD22C,.123*%
%ADD17R,.044X.016*%
%ADD49R,.028X.032*%
%ADD53R,.054X.026*%
%ADD43R,.014X.056*%
%ADD40R,.018X.052*%
%ADD37R,.054X.044*%
%ADD55C,.315*%
%ADD47R,.044X.054*%
%ADD42R,.062X.046*%
%ADD41R,.022X.068*%
%ADD38R,.014X.059*%
%ADD46R,.099X.067*%
%AMMACRO28*
4,1,28,.00748,-.00052,
.00984,-.00052,
.00984,-.00603,
.009782,-.006705,
.009607,-.007359,
.009321,-.007974,
.008933,-.008529,
.008455,-.009009,
.0079,-.009398,
.007286,-.009685,
.006632,-.009861,
.005957,-.00992,
.00591,-.00992,
-.00591,-.00992,
-.006585,-.009869,
-.007242,-.009701,
-.007859,-.009421,
-.008418,-.009039,
-.008903,-.008565,
-.009297,-.008015,
-.009591,-.007404,
-.009773,-.006751,
-.00984,-.006077,
-.00984,-.00603,
-.00984,-.00052,
-.00748,-.00052,
-.00748,.00991,
.00748,.00991,
.00748,-.00052,
0.0*
%
%ADD28MACRO28*%
%AMMACRO21*
4,1,28,-.00052,-.00748,
-.00052,-.00984,
-.00603,-.00984,
-.006705,-.009782,
-.007359,-.009607,
-.007974,-.009321,
-.008529,-.008933,
-.009009,-.008455,
-.009398,-.0079,
-.009685,-.007286,
-.009861,-.006632,
-.00992,-.005957,
-.00992,-.00591,
-.00992,.00591,
-.009869,.006585,
-.009701,.007242,
-.009421,.007859,
-.009039,.008418,
-.008565,.008903,
-.008015,.009297,
-.007404,.009591,
-.006751,.009773,
-.006077,.00984,
-.00603,.00984,
-.00052,.00984,
-.00052,.00748,
.00991,.00748,
.00991,-.00748,
-.00052,-.00748,
0.0*
%
%ADD21MACRO21*%
%AMMACRO27*
4,1,28,.00748,.00051,
.00984,.00051,
.00984,.00602,
.009782,.006695,
.009607,.007349,
.009321,.007964,
.008933,.008519,
.008455,.008998,
.0079,.009388,
.007287,.009675,
.006632,.009851,
.005958,.00991,
.00591,.00991,
-.00591,.00991,
-.006585,.009859,
-.007242,.009691,
-.007859,.009411,
-.008418,.009029,
-.008903,.008555,
-.009297,.008005,
-.00959,.007394,
-.009773,.006742,
-.00984,.006068,
-.00984,.00602,
-.00984,.00051,
-.00748,.00051,
-.00748,-.00992,
.00748,-.00992,
.00748,.00051,
0.0*
%
%ADD27MACRO27*%
%AMMACRO20*
4,1,28,.00051,-.00748,
.00051,-.00984,
.00602,-.00984,
.006695,-.009782,
.007349,-.009607,
.007964,-.009321,
.008519,-.008933,
.008998,-.008455,
.009388,-.0079,
.009675,-.007287,
.009851,-.006632,
.00991,-.005958,
.00991,-.00591,
.00991,.00591,
.009859,.006585,
.009691,.007242,
.009411,.007859,
.009029,.008418,
.008555,.008903,
.008005,.009297,
.007394,.00959,
.006742,.009773,
.006068,.00984,
.00602,.00984,
.00051,.00984,
.00051,.00748,
-.00992,.00748,
-.00992,-.00748,
.00051,-.00748,
0.0*
%
%ADD20MACRO20*%
%ADD56C,.006*%
G75*
%LPD*%
G75*
G54D10*
X38780Y232598D03*
Y239291D03*
Y252598D03*
Y259291D03*
Y272598D03*
Y279291D03*
Y292598D03*
Y299291D03*
X48780Y232598D03*
Y239291D03*
Y252598D03*
Y259291D03*
Y272598D03*
Y279291D03*
Y292598D03*
Y299291D03*
G54D20*
X181388Y227723D03*
X215984Y300500D03*
X224484D03*
X233484D03*
X224484Y305000D03*
X233484D03*
X215984D03*
X390484Y300500D03*
X372984D03*
X381484D03*
X390484Y305000D03*
X381484D03*
X372984D03*
X421503Y433500D03*
X530984Y300500D03*
Y305500D03*
X539984Y300500D03*
X548984D03*
X539984Y305500D03*
X548984D03*
X578984Y433500D03*
X688465Y300500D03*
X697465D03*
X706465D03*
X688465Y305500D03*
X697465D03*
X706465D03*
X800484Y330000D03*
Y335000D03*
Y341000D03*
Y346500D03*
Y352000D03*
X811484Y341000D03*
Y357000D03*
Y362000D03*
X837484Y332500D03*
X940484Y306500D03*
X940680Y310885D03*
X941180Y352385D03*
X1049484Y129000D03*
X1060484Y142000D03*
X1049484Y137500D03*
X1044984Y151000D03*
X1080327Y359443D03*
X1103484Y180000D03*
Y183500D03*
X1140779Y143734D03*
X1153484Y154000D03*
G54D11*
X33780Y334724D03*
Y324724D03*
X38780Y319724D03*
Y329724D03*
Y339724D03*
X33780Y344724D03*
X38780Y349724D03*
X48780Y319724D03*
Y329724D03*
Y339724D03*
X43780Y314724D03*
Y324724D03*
Y334724D03*
X48780Y349724D03*
X43780Y344724D03*
G54D21*
X178421Y227723D03*
X213017Y300500D03*
Y305000D03*
X221517Y300500D03*
X230517D03*
X221517Y305000D03*
X230517D03*
X387517Y300500D03*
X370017D03*
X378517D03*
X387517Y305000D03*
X378517D03*
X370017D03*
X418536Y433500D03*
X528017Y300500D03*
X537017D03*
Y305500D03*
X528017D03*
X546017Y300500D03*
Y305500D03*
X576017Y433500D03*
X685498Y300500D03*
Y305500D03*
X694498Y300500D03*
X703498D03*
X694498Y305500D03*
X703498D03*
X797517Y330000D03*
Y335000D03*
Y341000D03*
Y346500D03*
Y352000D03*
X834517Y332500D03*
X808517Y341000D03*
Y357000D03*
Y362000D03*
X937517Y306500D03*
X937713Y310885D03*
X938213Y352385D03*
X1042017Y151000D03*
X1046517Y129000D03*
X1057517Y142000D03*
X1046517Y137500D03*
X1100517Y180000D03*
Y183500D03*
X1077360Y359443D03*
X1137812Y143734D03*
X1150517Y154000D03*
G54D30*
X223819Y447516D03*
X361000Y300516D03*
X381299Y447516D03*
X397047Y300516D03*
X409000D03*
X538780Y447516D03*
X554528Y300516D03*
X549500Y447516D03*
X712009Y300516D03*
X696261Y447516D03*
X826000Y263016D03*
X831000D03*
X811000Y273016D03*
X811500Y323516D03*
X815500D03*
X823500D03*
X827000Y355016D03*
X832500D03*
X856000Y263016D03*
X846000D03*
X851000D03*
X841000D03*
X836000D03*
X852000Y331016D03*
X847500Y357016D03*
X853000D03*
X874000Y353016D03*
X883000D03*
X919500Y278016D03*
X904500Y294516D03*
X908000Y322516D03*
X924500Y358016D03*
X933000Y278016D03*
X926000D03*
X947000Y297016D03*
X940000D03*
X933196Y312401D03*
Y347901D03*
X1067500Y156516D03*
X1077500Y114016D03*
X1076800Y407016D03*
X1080300D03*
X1114000Y142016D03*
X1104500Y140016D03*
X1146760Y168336D03*
G54D12*
X33780Y314724D03*
G54D40*
X852240Y340177D03*
X848500D03*
X844760D03*
Y349823D03*
X852240D03*
X923740Y341177D03*
X920000D03*
X916260D03*
Y350823D03*
X923740D03*
G54D22*
X178819Y277204D03*
X193819D03*
X253819D03*
X268819D03*
X336299D03*
X351299D03*
X411299D03*
X426299D03*
X493780D03*
X508780D03*
X568780D03*
X583780D03*
X651261D03*
X666261D03*
X726261D03*
X741261D03*
G54D31*
X223819Y450483D03*
X361000Y303483D03*
X381299Y450483D03*
X397047Y303483D03*
X409000D03*
X538780Y450483D03*
X554528Y303483D03*
X549500Y450483D03*
X712009Y303483D03*
X696261Y450483D03*
X826000Y265983D03*
X831000D03*
X811000Y275983D03*
X811500Y326483D03*
X815500D03*
X823500D03*
X827000Y357983D03*
X832500D03*
X856000Y265983D03*
X846000D03*
X851000D03*
X841000D03*
X836000D03*
X852000Y333983D03*
X847500Y359983D03*
X853000D03*
X874000Y355983D03*
X883000D03*
X904500Y297483D03*
X919500Y280983D03*
X908000Y325483D03*
X924500Y360983D03*
X947000Y299983D03*
X940000D03*
X933000Y280983D03*
X926000D03*
X933196Y315368D03*
Y350868D03*
X1067500Y159483D03*
X1077500Y116983D03*
X1076800Y409983D03*
X1080300D03*
X1114000Y144983D03*
X1104500Y142983D03*
X1146760Y171303D03*
G54D13*
X60600Y335500D03*
X68403Y323700D03*
X69745Y350042D03*
X154840Y244730D03*
X128500Y426000D03*
X178265Y213443D03*
X175976Y218775D03*
X166068Y238749D03*
X173869Y228168D03*
X178329Y232900D03*
X160017Y237764D03*
X185954Y226083D03*
X171302Y333471D03*
X163247Y335500D03*
X179400Y326800D03*
X183539Y518000D03*
Y498000D03*
X171939D03*
Y518000D03*
X246000Y238500D03*
X231539Y518000D03*
Y498000D03*
X219939D03*
Y518000D03*
X267939Y498000D03*
Y518000D03*
X279539D03*
Y498000D03*
X329419D03*
Y518000D03*
X341019D03*
Y498000D03*
X369925Y287357D03*
X378479Y314111D03*
X389019Y518000D03*
Y498000D03*
X377419D03*
Y518000D03*
X402000Y238000D03*
X398500Y247000D03*
X421594Y438360D03*
X432000Y427600D03*
X437019Y518000D03*
Y498000D03*
X425419D03*
Y518000D03*
X498500Y498000D03*
Y518000D03*
X486900Y498000D03*
Y518000D03*
X535000Y295900D03*
X534900Y498000D03*
Y518000D03*
X544500Y450575D03*
X546500Y498000D03*
Y518000D03*
X575925Y425500D03*
X578984Y438000D03*
X594500Y498000D03*
Y518000D03*
X582900D03*
Y498000D03*
X605600Y448446D03*
X647975Y37000D03*
X660200Y56800D03*
X652300D03*
X655981Y518000D03*
Y498000D03*
X644381Y518000D03*
Y498000D03*
X684525Y32500D03*
X690075Y39500D03*
X683600Y56800D03*
X676000D03*
X668100D03*
X680400Y310500D03*
X703740Y41000D03*
X707000Y32000D03*
X694425Y29500D03*
X693000Y56600D03*
X706000Y61975D03*
X703740Y54118D03*
X703981Y518000D03*
Y498000D03*
X692381Y518000D03*
Y498000D03*
X740381Y518000D03*
Y498000D03*
X761560Y38500D03*
Y30000D03*
Y55500D03*
Y47000D03*
Y64000D03*
X753500Y326000D03*
X753020Y338500D03*
X754000Y356957D03*
X753550Y344161D03*
X759000Y365500D03*
X775425Y364500D03*
X753000Y366500D03*
X766240Y366446D03*
X751981Y498000D03*
Y518000D03*
X784855Y265184D03*
X790000Y259612D03*
X794900Y265979D03*
X798500Y272600D03*
X806000Y265075D03*
X790730Y351839D03*
X791000Y362000D03*
X791563Y342917D03*
X833500Y281000D03*
X815500Y281500D03*
X823206Y281207D03*
X811000Y286000D03*
X815000Y318500D03*
X827500D03*
X833500Y337000D03*
X819500Y336500D03*
X842075Y158924D03*
X843000Y167000D03*
X849500Y281500D03*
X841409Y280566D03*
X853000Y303500D03*
X842600Y317600D03*
X860000Y348000D03*
X879038Y271576D03*
X890676Y272620D03*
X871049Y266946D03*
X872500Y301906D03*
X871000Y348000D03*
X869000Y360500D03*
X903939Y272864D03*
X920899Y272824D03*
X913078Y271503D03*
X915143Y288612D03*
X914500Y303911D03*
X905819Y302819D03*
X898500Y285686D03*
X920000Y320135D03*
X910992Y361075D03*
X930086Y272986D03*
X945201Y272656D03*
X937676Y268356D03*
X932500Y305385D03*
X952000Y286500D03*
X945500Y319000D03*
X942546Y357925D03*
X1043500Y111500D03*
X1034500Y145000D03*
X1039500Y134500D03*
X1043936Y145745D03*
X1019040Y157310D03*
X1022168Y161783D03*
X1017909Y151424D03*
X1024340Y139500D03*
X1016614Y190267D03*
X1039016Y189075D03*
Y183027D03*
X1022000Y171200D03*
X1019700Y166600D03*
X1063500Y111500D03*
X1049356Y143900D03*
X1054500Y148500D03*
X1073154Y140800D03*
X1057500Y155877D03*
X1062500Y191500D03*
X1067701Y270442D03*
X1061600Y276242D03*
X1067679Y317942D03*
X1061600Y323742D03*
X1067707Y365442D03*
X1067531Y412942D03*
X1067730Y460352D03*
X1061600Y466242D03*
X1067866Y507629D03*
X1061600Y513742D03*
X1066500Y538000D03*
Y553000D03*
X1092000Y82500D03*
X1095500Y117075D03*
X1085300Y114016D03*
X1082000Y143600D03*
X1094500Y143144D03*
X1102000Y148000D03*
X1098500Y156937D03*
X1095500Y183500D03*
X1096000Y170500D03*
Y165000D03*
X1092000Y338800D03*
X1095575Y358640D03*
X1091100Y386400D03*
X1095575Y406310D03*
X1130125Y135940D03*
X1121238Y144500D03*
X1120524Y138457D03*
X1123500Y187000D03*
X1108000Y172000D03*
X1113368Y171619D03*
X1113129Y165719D03*
X1114500Y188700D03*
X1131476Y169294D03*
X1133000Y198000D03*
X1117206Y231741D03*
X1117290Y224241D03*
X1106106Y231741D03*
X1114452Y538000D03*
X1123669D03*
X1114452Y553000D03*
X1123669D03*
X1158200Y137700D03*
X1150425Y147401D03*
X1143490Y183560D03*
X1152500Y186500D03*
X1135203Y266860D03*
X1135403Y314360D03*
Y361979D03*
X1135190Y408965D03*
X1135404Y457228D03*
X1135622Y467732D03*
X1188600Y166000D03*
X1177521Y165952D03*
X1165070Y328750D03*
X1193411D03*
X1177836Y349234D03*
X1165190Y471250D03*
X1179500Y476750D03*
Y469750D03*
X1177925Y491734D03*
X1193840Y471250D03*
X1271500Y282000D03*
X1270000Y290000D03*
G54D41*
X865000Y338900D03*
Y318100D03*
X880000Y338900D03*
X875000D03*
X870000D03*
Y318100D03*
X875000D03*
X880000D03*
G54D50*
X1086243Y343943D03*
X1080443D03*
X1086243Y352443D03*
X1080443D03*
X1086243Y392500D03*
X1080443D03*
X1086243Y399943D03*
X1080443D03*
G54D14*
X147234Y239563D03*
Y232563D03*
X1063500Y124500D03*
Y117500D03*
G54D23*
X165539Y539000D03*
X213539D03*
X261539D03*
X323019D03*
X371019D03*
X419019D03*
X480500D03*
X528500D03*
X576500D03*
X637981D03*
X685981D03*
X733981D03*
G54D32*
X268000Y220315D03*
X312500D03*
X357000D03*
X428500D03*
X472500D03*
X516500D03*
X578500D03*
X622500D03*
X666500D03*
X735981D03*
X779981D03*
X823981D03*
G54D42*
X866000Y370200D03*
Y381800D03*
X847000Y370200D03*
Y381800D03*
X856500Y370200D03*
Y381800D03*
X885000Y370200D03*
Y381800D03*
X894500Y370200D03*
Y381800D03*
X875500Y370200D03*
Y381800D03*
X904000Y370200D03*
Y381800D03*
X923500Y370200D03*
Y381800D03*
X913500Y370200D03*
Y381800D03*
X933000Y370200D03*
Y381800D03*
X942500Y370200D03*
Y381800D03*
X952000Y370200D03*
Y381800D03*
G54D51*
X1086343Y368243D03*
Y359643D03*
Y415743D03*
Y407143D03*
G54D15*
X152016Y331000D03*
Y335500D03*
Y350500D03*
Y346500D03*
X178390Y223523D03*
X213016Y309500D03*
X221516D03*
X230516D03*
X387516D03*
X370016D03*
X378516D03*
X424035Y457500D03*
X537016Y310500D03*
X528016D03*
X546016D03*
X575516Y457500D03*
X685497Y310500D03*
X694497D03*
X703497D03*
X745016Y338500D03*
Y334500D03*
Y324500D03*
Y328500D03*
X732016Y338500D03*
Y328500D03*
X745016Y342500D03*
Y347700D03*
Y353200D03*
Y361500D03*
X775516Y369500D03*
X797516Y357000D03*
Y362000D03*
X824016Y334000D03*
X834516Y323500D03*
Y328000D03*
X937712Y315385D03*
X938212Y347885D03*
X1034516Y139500D03*
X1046516Y125500D03*
X1060016Y130500D03*
X1070516Y114000D03*
X1060016Y134000D03*
X1046516Y133600D03*
X1088016Y167500D03*
Y174500D03*
X1100516Y165000D03*
Y168500D03*
X1088016Y164000D03*
Y171000D03*
X1077359Y363443D03*
X1137516Y196500D03*
Y200500D03*
G54D33*
X268000Y240000D03*
X312500D03*
X357000D03*
X428500D03*
X472500D03*
X516500D03*
X578500D03*
X622500D03*
X666500D03*
X735981D03*
X779981D03*
X823981D03*
G54D24*
X185224Y539000D03*
X233224D03*
X281224D03*
X342704D03*
X390704D03*
X438704D03*
X500185D03*
X548185D03*
X596185D03*
X657666D03*
X705666D03*
X753666D03*
G54D43*
X933357Y322596D03*
X935916D03*
X938476D03*
X941035D03*
Y340174D03*
X938476D03*
X935916D03*
X933357D03*
G54D52*
X1092425Y354000D03*
X1095575D03*
X1092425Y401500D03*
X1095575D03*
G54D34*
X247441Y303575D03*
Y300425D03*
X404821Y303575D03*
Y300425D03*
X562402Y303575D03*
Y300425D03*
X719883Y303575D03*
Y300425D03*
G54D16*
X154983Y331000D03*
Y335500D03*
Y350500D03*
Y346500D03*
X181357Y223523D03*
X215983Y309500D03*
X224483D03*
X233483D03*
X390483D03*
X372983D03*
X381483D03*
X427002Y457500D03*
X530983Y310500D03*
X548983D03*
X539983D03*
X578483Y457500D03*
X688464Y310500D03*
X697464D03*
X706464D03*
X734983Y338500D03*
Y328500D03*
X747983Y338500D03*
Y334500D03*
Y324500D03*
Y328500D03*
Y342500D03*
Y347700D03*
Y353200D03*
Y361500D03*
X800483Y357000D03*
Y362000D03*
X778483Y369500D03*
X826983Y334000D03*
X837483Y323500D03*
Y328000D03*
X940679Y315385D03*
X941179Y347885D03*
X1037483Y139500D03*
X1049483Y125500D03*
X1062983Y130500D03*
Y134000D03*
X1049483Y133600D03*
X1073483Y114000D03*
X1090983Y167500D03*
Y174500D03*
Y164000D03*
Y171000D03*
X1080326Y363443D03*
X1103483Y165000D03*
Y168500D03*
X1140483Y196500D03*
Y200500D03*
G54D25*
X211000Y26000D03*
X954550Y77250D03*
X1155350Y561140D03*
G54D53*
X1144019Y149734D03*
X1134571D03*
G54D17*
X129370Y414500D03*
X150630D03*
X760280Y336484D03*
Y359516D03*
Y356957D03*
Y354398D03*
Y351839D03*
Y349280D03*
Y346720D03*
Y344161D03*
Y341602D03*
Y339043D03*
X782720Y336484D03*
Y339043D03*
Y341602D03*
Y344161D03*
Y346720D03*
Y349280D03*
Y351839D03*
Y354398D03*
Y356957D03*
Y359516D03*
G54D35*
X253819Y477204D03*
X411299D03*
X568780D03*
X726261D03*
G54D44*
X1011000Y98000D03*
X1151000Y90400D03*
G54D26*
X208071Y267204D03*
X200197D03*
X215945D03*
X231693D03*
X223819D03*
X239567D03*
X247441D03*
X357677D03*
X365551D03*
X373425D03*
X389173D03*
X381299D03*
X404921D03*
X397047D03*
X523032D03*
X515158D03*
X530906D03*
X538780D03*
X546654D03*
X562402D03*
X554528D03*
X680513D03*
X672639D03*
X688387D03*
X704135D03*
X696261D03*
X712009D03*
X719883D03*
G54D27*
X208071Y303484D03*
X239567D03*
X223819Y458484D03*
X251500Y303484D03*
X365551D03*
X381299Y458484D03*
X412019Y450484D03*
X432019Y457484D03*
X523032Y303484D03*
X538780Y458484D03*
X569500Y450484D03*
X589500Y451984D03*
X680513Y303484D03*
X696261Y458484D03*
X724000Y303484D03*
X826000Y275984D03*
X831000D03*
X816000D03*
X821000D03*
X806500Y282484D03*
X819500Y326484D03*
X827500D03*
X821500Y357984D03*
X846000Y275984D03*
X851000D03*
X856000D03*
X841000D03*
X836000D03*
X864500Y355984D03*
X843000Y359984D03*
X875000Y296984D03*
X880000D03*
X870000D03*
X888000Y280984D03*
X877500D03*
X884000D03*
X894500D03*
X875000Y309984D03*
X880000D03*
X870000D03*
X878000Y355984D03*
X869000D03*
X898500Y280984D03*
X909500Y297484D03*
X914500D03*
X909000Y280984D03*
X905000D03*
X915500D03*
X903500Y325484D03*
X909500Y335484D03*
X912500Y325484D03*
X915500Y360984D03*
X920000D03*
X947000Y280984D03*
X940000D03*
X947000Y290984D03*
X940000D03*
X933000D03*
X938000Y360984D03*
X1070000Y188984D03*
X1077000Y184484D03*
X1082500D03*
X1073500Y188984D03*
X1110000Y144984D03*
X1141500Y117484D03*
X1132000Y180484D03*
G54D36*
X418582Y448000D03*
X426456Y444260D03*
Y451740D03*
X576063Y448000D03*
X583937Y444260D03*
Y451740D03*
X890063Y298740D03*
Y291260D03*
X897937Y295000D03*
X908937Y345500D03*
X901063Y349240D03*
Y341760D03*
X1106063Y154500D03*
X1113937Y150760D03*
Y158240D03*
X1144563Y138000D03*
X1152437Y134260D03*
Y141740D03*
G54D45*
X1011000Y118000D03*
Y108000D03*
X1161000Y90400D03*
X1171000D03*
G54D54*
X1183561Y130467D03*
Y156451D03*
G54D18*
X127795Y414500D03*
G54D28*
X208071Y300517D03*
X239567D03*
X223819Y455517D03*
X251500Y300517D03*
X365551D03*
X381299Y455517D03*
X412019Y447517D03*
X432019Y454517D03*
X523032Y300517D03*
X538780Y455517D03*
X569500Y447517D03*
X589500Y449017D03*
X680513Y300517D03*
X696261Y455517D03*
X724000Y300517D03*
X826000Y273017D03*
X831000D03*
X816000D03*
X821000D03*
X806500Y279517D03*
X819500Y323517D03*
X827500D03*
X821500Y355017D03*
X846000Y273017D03*
X851000D03*
X856000D03*
X841000D03*
X836000D03*
X864500Y353017D03*
X843000Y357017D03*
X888000Y278017D03*
X877500D03*
X884000D03*
X894500D03*
X875000Y307017D03*
X880000D03*
X875000Y294017D03*
X880000D03*
X870000Y307017D03*
Y294017D03*
X878000Y353017D03*
X869000D03*
X898500Y278017D03*
X909000D03*
X905000D03*
X915500D03*
X909500Y294517D03*
X914500D03*
X903500Y322517D03*
X909500Y332517D03*
X912500Y322517D03*
X915500Y358017D03*
X920000D03*
X947000Y278017D03*
X940000D03*
X947000Y288017D03*
X940000D03*
X933000D03*
X938000Y358017D03*
X1070000Y186017D03*
X1077000Y181517D03*
X1082500D03*
X1073500Y186017D03*
X1110000Y142017D03*
X1141500Y114517D03*
X1132000Y177517D03*
G54D46*
X1046126Y100500D03*
X1061874D03*
X1100126Y107000D03*
X1115874D03*
G54D55*
X1226024Y174429D03*
Y399429D03*
G54D37*
X563000Y453240D03*
Y445760D03*
X1110500Y117260D03*
Y124740D03*
X1148000Y206260D03*
Y213740D03*
X1140500Y206260D03*
Y213740D03*
X1155500Y206260D03*
Y213740D03*
X1167600Y189560D03*
Y197040D03*
G54D19*
X152205Y414500D03*
G54D56*
G01X-297025Y-1013390D02*
Y1828909D01*
X3691357D01*
Y-1013390D01*
X-297025D01*
G01X4093Y-769672D02*
Y-844672D01*
X504093D01*
Y-769672D01*
X4093D01*
G01X16093Y-834672D02*
Y-839672D01*
G01X14636Y-834672D02*
X17550D01*
G01X22460Y-839672D02*
X19926D01*
Y-834672D01*
X22460D01*
G01X21446Y-837089D02*
X19926D01*
G01X25026Y-834672D02*
Y-839672D01*
X27560D01*
G01X31393Y-839839D02*
X31266Y-839755D01*
Y-839589D01*
X31393Y-839505D01*
X31520Y-839589D01*
Y-839755D01*
X31393Y-839839D01*
G01Y-837589D02*
X31266Y-837505D01*
Y-837339D01*
X31393Y-837255D01*
X31520Y-837339D01*
Y-837505D01*
X31393Y-837589D01*
G01X36176Y-841339D02*
X35543Y-840505D01*
X35226Y-839672D01*
Y-836339D01*
X35543Y-835505D01*
X36176Y-834672D01*
G01X41593D02*
X41086Y-834839D01*
X40706Y-835255D01*
X40453Y-835755D01*
X40263Y-836422D01*
X40200Y-837172D01*
X40263Y-837922D01*
X40453Y-838589D01*
X40706Y-839089D01*
X41086Y-839505D01*
X41593Y-839672D01*
X42100Y-839505D01*
X42480Y-839089D01*
X42733Y-838589D01*
X42923Y-837922D01*
X42986Y-837172D01*
X42923Y-836422D01*
X42733Y-835755D01*
X42480Y-835255D01*
X42100Y-834839D01*
X41593Y-834672D01*
G01X45300Y-838672D02*
X45680Y-839255D01*
X46186Y-839589D01*
X46756Y-839672D01*
X47263Y-839589D01*
X47770Y-839172D01*
X48086Y-838672D01*
X48150Y-838172D01*
X48023Y-837589D01*
X47580Y-837172D01*
X47136Y-837005D01*
X46566D01*
G01X47136D02*
X47516Y-836755D01*
X47833Y-836339D01*
X47960Y-835839D01*
X47833Y-835339D01*
X47516Y-834922D01*
X46946Y-834672D01*
X46376Y-834755D01*
X45806Y-835089D01*
G01X52110Y-841339D02*
X52743Y-840505D01*
X53060Y-839672D01*
Y-836339D01*
X52743Y-835505D01*
X52110Y-834672D01*
G01X55500Y-838672D02*
X55880Y-839255D01*
X56386Y-839589D01*
X56956Y-839672D01*
X57463Y-839589D01*
X57970Y-839172D01*
X58286Y-838672D01*
X58350Y-838172D01*
X58223Y-837589D01*
X57780Y-837172D01*
X57336Y-837005D01*
X56766D01*
G01X57336D02*
X57716Y-836755D01*
X58033Y-836339D01*
X58160Y-835839D01*
X58033Y-835339D01*
X57716Y-834922D01*
X57146Y-834672D01*
X56576Y-834755D01*
X56006Y-835089D01*
G01X60790Y-835505D02*
X61170Y-835005D01*
X61613Y-834755D01*
X62120Y-834672D01*
X62753Y-834839D01*
X63196Y-835255D01*
X63323Y-835755D01*
X63260Y-836255D01*
X63006Y-836672D01*
X61740Y-837505D01*
X61170Y-838089D01*
X60790Y-838922D01*
X60663Y-839672D01*
X63323D01*
G01X66966D02*
X67093Y-838589D01*
X67283Y-837672D01*
X67536Y-836839D01*
X67853Y-835922D01*
X68360Y-834672D01*
X65826D01*
G01X71370Y-838005D02*
X73016D01*
G01X76090Y-835505D02*
X76470Y-835005D01*
X76913Y-834755D01*
X77420Y-834672D01*
X78053Y-834839D01*
X78496Y-835255D01*
X78623Y-835755D01*
X78560Y-836255D01*
X78306Y-836672D01*
X77040Y-837505D01*
X76470Y-838089D01*
X76090Y-838922D01*
X75963Y-839672D01*
X78623D01*
G01X81000Y-838672D02*
X81380Y-839255D01*
X81886Y-839589D01*
X82456Y-839672D01*
X82963Y-839589D01*
X83470Y-839172D01*
X83786Y-838672D01*
X83850Y-838172D01*
X83723Y-837589D01*
X83280Y-837172D01*
X82836Y-837005D01*
X82266D01*
G01X82836D02*
X83216Y-836755D01*
X83533Y-836339D01*
X83660Y-835839D01*
X83533Y-835339D01*
X83216Y-834922D01*
X82646Y-834672D01*
X82076Y-834755D01*
X81506Y-835089D01*
G01X88253Y-839672D02*
Y-834672D01*
X85910Y-838255D01*
X89076D01*
G01X91200Y-838922D02*
X91580Y-839339D01*
X92023Y-839589D01*
X92593Y-839672D01*
X93163Y-839505D01*
X93606Y-839172D01*
X93923Y-838589D01*
X93986Y-837922D01*
X93860Y-837255D01*
X93543Y-836839D01*
X93100Y-836505D01*
X92656Y-836422D01*
X92213Y-836505D01*
X91643Y-836839D01*
X91833Y-834672D01*
X93543D01*
G01X101590Y-839672D02*
Y-834672D01*
X103996D01*
G01X103110Y-837089D02*
X101590D01*
G01X106310Y-839672D02*
X107893Y-834672D01*
X109476Y-839672D01*
G01X108906Y-837922D02*
X106880D01*
G01X111663Y-839672D02*
X114323Y-834672D01*
G01X111663D02*
X114323Y-839672D01*
G01X118093Y-839839D02*
X117966Y-839755D01*
Y-839589D01*
X118093Y-839505D01*
X118220Y-839589D01*
Y-839755D01*
X118093Y-839839D01*
G01Y-837589D02*
X117966Y-837505D01*
Y-837339D01*
X118093Y-837255D01*
X118220Y-837339D01*
Y-837505D01*
X118093Y-837589D01*
G01X122876Y-841339D02*
X122243Y-840505D01*
X121926Y-839672D01*
Y-836339D01*
X122243Y-835505D01*
X122876Y-834672D01*
G01X128293D02*
X127786Y-834839D01*
X127406Y-835255D01*
X127153Y-835755D01*
X126963Y-836422D01*
X126900Y-837172D01*
X126963Y-837922D01*
X127153Y-838589D01*
X127406Y-839089D01*
X127786Y-839505D01*
X128293Y-839672D01*
X128800Y-839505D01*
X129180Y-839089D01*
X129433Y-838589D01*
X129623Y-837922D01*
X129686Y-837172D01*
X129623Y-836422D01*
X129433Y-835755D01*
X129180Y-835255D01*
X128800Y-834839D01*
X128293Y-834672D01*
G01X132000Y-838672D02*
X132380Y-839255D01*
X132886Y-839589D01*
X133456Y-839672D01*
X133963Y-839589D01*
X134470Y-839172D01*
X134786Y-838672D01*
X134850Y-838172D01*
X134723Y-837589D01*
X134280Y-837172D01*
X133836Y-837005D01*
X133266D01*
G01X133836D02*
X134216Y-836755D01*
X134533Y-836339D01*
X134660Y-835839D01*
X134533Y-835339D01*
X134216Y-834922D01*
X133646Y-834672D01*
X133076Y-834755D01*
X132506Y-835089D01*
G01X138810Y-841339D02*
X139443Y-840505D01*
X139760Y-839672D01*
Y-836339D01*
X139443Y-835505D01*
X138810Y-834672D01*
G01X142200Y-838672D02*
X142580Y-839255D01*
X143086Y-839589D01*
X143656Y-839672D01*
X144163Y-839589D01*
X144670Y-839172D01*
X144986Y-838672D01*
X145050Y-838172D01*
X144923Y-837589D01*
X144480Y-837172D01*
X144036Y-837005D01*
X143466D01*
G01X144036D02*
X144416Y-836755D01*
X144733Y-836339D01*
X144860Y-835839D01*
X144733Y-835339D01*
X144416Y-834922D01*
X143846Y-834672D01*
X143276Y-834755D01*
X142706Y-835089D01*
G01X147616Y-839089D02*
X148060Y-839505D01*
X148566Y-839672D01*
X149073Y-839505D01*
X149516Y-839005D01*
X149833Y-838255D01*
X149960Y-837505D01*
Y-836589D01*
X149833Y-835839D01*
X149516Y-835172D01*
X149136Y-834839D01*
X148693Y-834672D01*
X148186Y-834839D01*
X147806Y-835172D01*
X147553Y-835672D01*
X147426Y-836339D01*
X147553Y-836922D01*
X147870Y-837505D01*
X148250Y-837839D01*
X148693Y-837922D01*
X149200Y-837755D01*
X149580Y-837339D01*
X149960Y-836589D01*
G01X153666Y-839672D02*
X153793Y-838589D01*
X153983Y-837672D01*
X154236Y-836839D01*
X154553Y-835922D01*
X155060Y-834672D01*
X152526D01*
G01X158070Y-838005D02*
X159716D01*
G01X162600Y-838672D02*
X162980Y-839255D01*
X163486Y-839589D01*
X164056Y-839672D01*
X164563Y-839589D01*
X165070Y-839172D01*
X165386Y-838672D01*
X165450Y-838172D01*
X165323Y-837589D01*
X164880Y-837172D01*
X164436Y-837005D01*
X163866D01*
G01X164436D02*
X164816Y-836755D01*
X165133Y-836339D01*
X165260Y-835839D01*
X165133Y-835339D01*
X164816Y-834922D01*
X164246Y-834672D01*
X163676Y-834755D01*
X163106Y-835089D01*
G01X167890Y-837589D02*
X168333Y-837005D01*
X168713Y-836672D01*
X169220Y-836505D01*
X169663Y-836672D01*
X169980Y-837005D01*
X170233Y-837505D01*
X170296Y-838089D01*
X170233Y-838589D01*
X169980Y-839089D01*
X169600Y-839505D01*
X169156Y-839672D01*
X168650Y-839505D01*
X168206Y-839005D01*
X167953Y-838255D01*
X167890Y-837422D01*
X168016Y-836339D01*
X168206Y-835755D01*
X168523Y-835172D01*
X168966Y-834755D01*
X169410Y-834672D01*
X169853Y-834839D01*
X170170Y-835255D01*
G01X174193Y-839672D02*
Y-834672D01*
X173433Y-835672D01*
G01Y-839672D02*
X174953D01*
G01X180053D02*
Y-834672D01*
X177710Y-838255D01*
X180876D01*
G01X199093Y-769672D02*
Y-844672D01*
G01Y-819672D02*
X302093D01*
Y-794672D01*
G01X199093D02*
X302093D01*
G01X309600Y-829672D02*
Y-824672D01*
X310866D01*
X311373Y-824922D01*
X311753Y-825255D01*
X312070Y-825755D01*
X312323Y-826339D01*
X312386Y-827172D01*
X312323Y-828005D01*
X312070Y-828589D01*
X311753Y-829089D01*
X311373Y-829422D01*
X310866Y-829672D01*
X309600D01*
G01X314510D02*
X316093Y-824672D01*
X317676Y-829672D01*
G01X317106Y-827922D02*
X315080D01*
G01X321193Y-824672D02*
Y-829672D01*
G01X319736Y-824672D02*
X322650D01*
G01X327560Y-829672D02*
X325026D01*
Y-824672D01*
X327560D01*
G01X326546Y-827089D02*
X325026D01*
G01X331393Y-829839D02*
X331266Y-829755D01*
Y-829589D01*
X331393Y-829505D01*
X331520Y-829589D01*
Y-829755D01*
X331393Y-829839D01*
G01Y-827589D02*
X331266Y-827505D01*
Y-827339D01*
X331393Y-827255D01*
X331520Y-827339D01*
Y-827505D01*
X331393Y-827589D01*
G01X304093Y-769672D02*
Y-844672D01*
G01X302093Y-769672D02*
Y-844672D01*
G01X304093Y-819672D02*
X504093D01*
G01X309726Y-804672D02*
Y-799672D01*
X311246D01*
X311753Y-799922D01*
X312133Y-800505D01*
X312260Y-801172D01*
X312133Y-801839D01*
X311816Y-802339D01*
X311246Y-802589D01*
X309726D01*
G01X314953Y-804839D02*
X317233Y-799672D01*
G01X319736Y-804672D02*
Y-799672D01*
X322650Y-804672D01*
Y-799672D01*
G01X326293Y-804839D02*
X326166Y-804755D01*
Y-804589D01*
X326293Y-804505D01*
X326420Y-804589D01*
Y-804755D01*
X326293Y-804839D01*
G01Y-802589D02*
X326166Y-802505D01*
Y-802339D01*
X326293Y-802255D01*
X326420Y-802339D01*
Y-802505D01*
X326293Y-802589D01*
G01X304093Y-794672D02*
X504093D01*
G01X309726Y-779672D02*
Y-774672D01*
X311246D01*
X311753Y-774922D01*
X312133Y-775505D01*
X312260Y-776172D01*
X312133Y-776839D01*
X311816Y-777339D01*
X311246Y-777589D01*
X309726D01*
G01X314826Y-779672D02*
Y-774672D01*
X316410D01*
X316916Y-774922D01*
X317233Y-775255D01*
X317360Y-775922D01*
X317233Y-776589D01*
X316853Y-777005D01*
X316410Y-777255D01*
X314826D01*
G01X316410D02*
X317360Y-779672D01*
G01X321193D02*
X320686Y-779589D01*
X320243Y-779255D01*
X319863Y-778755D01*
X319610Y-778172D01*
X319483Y-777505D01*
Y-776839D01*
X319610Y-776172D01*
X319863Y-775589D01*
X320243Y-775089D01*
X320686Y-774755D01*
X321193Y-774672D01*
X321700Y-774755D01*
X322143Y-775089D01*
X322523Y-775589D01*
X322776Y-776172D01*
X322903Y-776839D01*
Y-777505D01*
X322776Y-778172D01*
X322523Y-778755D01*
X322143Y-779255D01*
X321700Y-779589D01*
X321193Y-779672D01*
G01X325026Y-778672D02*
X325343Y-779172D01*
X325723Y-779505D01*
X326166Y-779672D01*
X326673Y-779505D01*
X327053Y-779172D01*
X327433Y-778672D01*
X327560Y-778005D01*
Y-774672D01*
G01X332660Y-779672D02*
X330126D01*
Y-774672D01*
X332660D01*
G01X331646Y-777089D02*
X330126D01*
G01X337886Y-775089D02*
X337506Y-774839D01*
X337063Y-774672D01*
X336556D01*
X335986Y-774922D01*
X335543Y-775339D01*
X335226Y-775839D01*
X334973Y-776672D01*
X334910Y-777422D01*
X335036Y-778172D01*
X335226Y-778672D01*
X335606Y-779172D01*
X336050Y-779505D01*
X336493Y-779672D01*
X336936D01*
X337380Y-779505D01*
X337760Y-779255D01*
X338076Y-778922D01*
G01X341593Y-774672D02*
Y-779672D01*
G01X340136Y-774672D02*
X343050D01*
G01X346693Y-779839D02*
X346566Y-779755D01*
Y-779589D01*
X346693Y-779505D01*
X346820Y-779589D01*
Y-779755D01*
X346693Y-779839D01*
G01Y-777589D02*
X346566Y-777505D01*
Y-777339D01*
X346693Y-777255D01*
X346820Y-777339D01*
Y-777505D01*
X346693Y-777589D01*
G01X419093Y-819672D02*
Y-844672D01*
G01X421726Y-822172D02*
Y-827172D01*
X424260D01*
G01X427333Y-822172D02*
X428853D01*
G01X428093D02*
Y-827172D01*
G01X427333D02*
X428853D01*
G01X433700Y-824505D02*
X433953Y-824255D01*
X434143Y-823839D01*
X434270Y-823255D01*
X434143Y-822755D01*
X433890Y-822422D01*
X433446Y-822172D01*
X431736D01*
Y-827172D01*
X433826D01*
X434270Y-826839D01*
X434523Y-826339D01*
X434650Y-825755D01*
X434523Y-825172D01*
X434143Y-824672D01*
X433700Y-824505D01*
X431736D01*
G01X438293Y-827339D02*
X438166Y-827255D01*
Y-827089D01*
X438293Y-827005D01*
X438420Y-827089D01*
Y-827255D01*
X438293Y-827339D01*
G01Y-825089D02*
X438166Y-825005D01*
Y-824839D01*
X438293Y-824755D01*
X438420Y-824839D01*
Y-825005D01*
X438293Y-825089D01*
G01X470106Y-847839D02*
X470213Y-847714D01*
X470293Y-847505D01*
X470346Y-847214D01*
X470293Y-846964D01*
X470186Y-846797D01*
X470000Y-846672D01*
X469280D01*
Y-849172D01*
X470160D01*
X470346Y-849005D01*
X470453Y-848755D01*
X470506Y-848464D01*
X470453Y-848172D01*
X470293Y-847922D01*
X470106Y-847839D01*
X469280D01*
G01X472573Y-849172D02*
Y-847505D01*
G01Y-847797D02*
X472466Y-847630D01*
X472306Y-847547D01*
X472120Y-847505D01*
X471933Y-847589D01*
X471773Y-847755D01*
X471666Y-848005D01*
X471613Y-848339D01*
X471666Y-848672D01*
X471773Y-848922D01*
X471933Y-849089D01*
X472120Y-849172D01*
X472306Y-849130D01*
X472466Y-849005D01*
X472573Y-848839D01*
G01X473893Y-848880D02*
X474026Y-849047D01*
X474213Y-849172D01*
X474373D01*
X474533Y-849089D01*
X474640Y-848964D01*
X474693Y-848797D01*
X474666Y-848547D01*
X474560Y-848422D01*
X474080Y-848172D01*
X473973Y-847880D01*
X474026Y-847672D01*
X474133Y-847547D01*
X474293Y-847505D01*
X474453Y-847547D01*
X474613Y-847672D01*
G01X476093Y-848047D02*
X476946D01*
X476866Y-847755D01*
X476733Y-847589D01*
X476546Y-847505D01*
X476360Y-847547D01*
X476200Y-847672D01*
X476093Y-847964D01*
X476040Y-848214D01*
Y-848464D01*
X476093Y-848714D01*
X476226Y-848964D01*
X476386Y-849130D01*
X476573Y-849172D01*
X476760Y-849089D01*
X476946Y-848839D01*
G01X478213Y-849172D02*
Y-846672D01*
G01Y-847922D02*
X478346Y-847672D01*
X478506Y-847547D01*
X478666Y-847505D01*
X478906Y-847589D01*
X479066Y-847755D01*
X479173Y-848047D01*
Y-848380D01*
X479120Y-848714D01*
X479013Y-848964D01*
X478826Y-849130D01*
X478666Y-849172D01*
X478506Y-849130D01*
X478346Y-849005D01*
X478213Y-848797D01*
G01X480893Y-849172D02*
X480733Y-849130D01*
X480573Y-848964D01*
X480466Y-848672D01*
X480413Y-848339D01*
X480466Y-848005D01*
X480573Y-847714D01*
X480733Y-847547D01*
X480893Y-847505D01*
X481053Y-847547D01*
X481213Y-847714D01*
X481320Y-848005D01*
X481346Y-848339D01*
X481320Y-848672D01*
X481213Y-848964D01*
X481053Y-849130D01*
X480893Y-849172D01*
G01X483573D02*
Y-847505D01*
G01Y-847797D02*
X483466Y-847630D01*
X483306Y-847547D01*
X483120Y-847505D01*
X482933Y-847589D01*
X482773Y-847755D01*
X482666Y-848005D01*
X482613Y-848339D01*
X482666Y-848672D01*
X482773Y-848922D01*
X482933Y-849089D01*
X483120Y-849172D01*
X483306Y-849130D01*
X483466Y-849005D01*
X483573Y-848839D01*
G01X484920Y-849172D02*
Y-847505D01*
G01Y-847839D02*
X485053Y-847672D01*
X485186Y-847547D01*
X485373Y-847505D01*
X485506Y-847547D01*
X485666Y-847672D01*
G01X487973Y-846672D02*
Y-849172D01*
G01Y-848797D02*
X487866Y-849005D01*
X487706Y-849130D01*
X487520Y-849172D01*
X487306Y-849089D01*
X487146Y-848880D01*
X487040Y-848630D01*
X487013Y-848339D01*
X487040Y-848047D01*
X487146Y-847797D01*
X487306Y-847589D01*
X487520Y-847505D01*
X487706Y-847547D01*
X487840Y-847630D01*
X487973Y-847797D01*
G01X491360Y-849172D02*
Y-846672D01*
X492026D01*
X492240Y-846797D01*
X492373Y-846964D01*
X492426Y-847297D01*
X492373Y-847630D01*
X492213Y-847839D01*
X492026Y-847964D01*
X491360D01*
G01X492026D02*
X492426Y-849172D01*
G01X493693Y-848047D02*
X494546D01*
X494466Y-847755D01*
X494333Y-847589D01*
X494146Y-847505D01*
X493960Y-847547D01*
X493800Y-847672D01*
X493693Y-847964D01*
X493640Y-848214D01*
Y-848464D01*
X493693Y-848714D01*
X493826Y-848964D01*
X493986Y-849130D01*
X494173Y-849172D01*
X494360Y-849089D01*
X494546Y-848839D01*
G01X495813Y-847505D02*
X496293Y-849172D01*
X496773Y-847505D01*
G01X498493Y-849255D02*
X498440Y-849214D01*
Y-849130D01*
X498493Y-849089D01*
X498546Y-849130D01*
Y-849214D01*
X498493Y-849255D01*
G01X500693Y-849172D02*
X500880Y-849130D01*
X501093Y-849005D01*
X501226Y-848797D01*
X501280Y-848505D01*
X501226Y-848214D01*
X501066Y-847964D01*
X500826Y-847839D01*
X500560D01*
X500400Y-847755D01*
X500266Y-847547D01*
X500213Y-847255D01*
X500293Y-846964D01*
X500480Y-846755D01*
X500693Y-846672D01*
X500906Y-846755D01*
X501093Y-846964D01*
X501173Y-847255D01*
X501120Y-847547D01*
X500986Y-847755D01*
X500826Y-847839D01*
X500560D01*
X500320Y-847964D01*
X500160Y-848214D01*
X500106Y-848505D01*
X500160Y-848797D01*
X500293Y-849005D01*
X500506Y-849130D01*
X500693Y-849172D01*
G01X503106Y-847839D02*
X503213Y-847714D01*
X503293Y-847505D01*
X503346Y-847214D01*
X503293Y-846964D01*
X503186Y-846797D01*
X503000Y-846672D01*
X502280D01*
Y-849172D01*
X503160D01*
X503346Y-849005D01*
X503453Y-848755D01*
X503506Y-848464D01*
X503453Y-848172D01*
X503293Y-847922D01*
X503106Y-847839D01*
X502280D01*
G01X465993Y-822172D02*
Y-827172D01*
G01X464536Y-822172D02*
X467450D01*
G01X471093Y-827172D02*
X470713Y-827089D01*
X470333Y-826755D01*
X470080Y-826172D01*
X469953Y-825505D01*
X470080Y-824839D01*
X470333Y-824255D01*
X470713Y-823922D01*
X471093Y-823839D01*
X471473Y-823922D01*
X471853Y-824255D01*
X472106Y-824839D01*
X472170Y-825505D01*
X472106Y-826172D01*
X471853Y-826755D01*
X471473Y-827089D01*
X471093Y-827172D01*
G01X476193D02*
X475813Y-827089D01*
X475433Y-826755D01*
X475180Y-826172D01*
X475053Y-825505D01*
X475180Y-824839D01*
X475433Y-824255D01*
X475813Y-823922D01*
X476193Y-823839D01*
X476573Y-823922D01*
X476953Y-824255D01*
X477206Y-824839D01*
X477270Y-825505D01*
X477206Y-826172D01*
X476953Y-826755D01*
X476573Y-827089D01*
X476193Y-827172D01*
G01X481293D02*
Y-822172D01*
G01X486393Y-827339D02*
X486266Y-827255D01*
Y-827089D01*
X486393Y-827005D01*
X486520Y-827089D01*
Y-827255D01*
X486393Y-827339D01*
G01Y-825089D02*
X486266Y-825005D01*
Y-824839D01*
X486393Y-824755D01*
X486520Y-824839D01*
Y-825005D01*
X486393Y-825089D01*
G01X462093Y-819672D02*
Y-844672D01*
G01Y-794672D02*
Y-819672D01*
G01X464726Y-802172D02*
Y-797172D01*
X466310D01*
X466816Y-797422D01*
X467133Y-797755D01*
X467260Y-798422D01*
X467133Y-799089D01*
X466753Y-799505D01*
X466310Y-799755D01*
X464726D01*
G01X466310D02*
X467260Y-802172D01*
G01X472360D02*
X469826D01*
Y-797172D01*
X472360D01*
G01X471346Y-799589D02*
X469826D01*
G01X474610Y-797172D02*
X476193Y-802172D01*
X477776Y-797172D01*
G01X481293Y-802339D02*
X481166Y-802255D01*
Y-802089D01*
X481293Y-802005D01*
X481420Y-802089D01*
Y-802255D01*
X481293Y-802339D01*
G01Y-800089D02*
X481166Y-800005D01*
Y-799839D01*
X481293Y-799755D01*
X481420Y-799839D01*
Y-800005D01*
X481293Y-800089D01*
G01X-297025Y-1013390D02*
Y1828909D01*
X3691357D01*
Y-1013390D01*
X-297025D01*
G01X16913Y-817022D02*
X18480D01*
Y-818912D01*
X18010Y-819542D01*
X17461Y-819962D01*
X16678Y-820172D01*
X15895Y-819962D01*
X15346Y-819542D01*
X14876Y-818912D01*
X14563Y-818177D01*
X14406Y-817337D01*
Y-816602D01*
X14563Y-815972D01*
X14876Y-815237D01*
X15346Y-814607D01*
X15816Y-814187D01*
X16443Y-813872D01*
X16991D01*
X17618Y-814082D01*
X18088Y-814502D01*
G01X21020Y-813872D02*
Y-818387D01*
X21333Y-819332D01*
X21960Y-819962D01*
X22743Y-820172D01*
X23526Y-819962D01*
X24153Y-819332D01*
X24466Y-818387D01*
Y-813872D01*
G01X28103D02*
X29983D01*
G01X29043D02*
Y-820172D01*
G01X28103D02*
X29983D01*
G01X33698Y-819332D02*
X34325Y-819857D01*
X35030Y-820172D01*
X35656D01*
X36283Y-819857D01*
X36753Y-819332D01*
X36988Y-818597D01*
X36831Y-817862D01*
X36440Y-817232D01*
X35735Y-816812D01*
X34795Y-816602D01*
X34246Y-816182D01*
X34011Y-815447D01*
X34168Y-814712D01*
X34560Y-814187D01*
X35108Y-813872D01*
X35656D01*
X36205Y-814082D01*
X36675Y-814607D01*
G01X39998Y-820172D02*
Y-813872D01*
G01X43288D02*
Y-820172D01*
G01Y-817022D02*
X39998D01*
G01X45985Y-820172D02*
X47943Y-813872D01*
X49901Y-820172D01*
G01X49196Y-817967D02*
X46690D01*
G01X52441Y-820172D02*
Y-813872D01*
X56045Y-820172D01*
Y-813872D01*
G01X65120Y-820172D02*
Y-813872D01*
X66686D01*
X67313Y-814187D01*
X67783Y-814607D01*
X68175Y-815237D01*
X68488Y-815972D01*
X68566Y-817022D01*
X68488Y-818072D01*
X68175Y-818807D01*
X67783Y-819437D01*
X67313Y-819857D01*
X66686Y-820172D01*
X65120D01*
G01X72203Y-813872D02*
X74083D01*
G01X73143D02*
Y-820172D01*
G01X72203D02*
X74083D01*
G01X77798Y-819332D02*
X78425Y-819857D01*
X79130Y-820172D01*
X79756D01*
X80383Y-819857D01*
X80853Y-819332D01*
X81088Y-818597D01*
X80931Y-817862D01*
X80540Y-817232D01*
X79835Y-816812D01*
X78895Y-816602D01*
X78346Y-816182D01*
X78111Y-815447D01*
X78268Y-814712D01*
X78660Y-814187D01*
X79208Y-813872D01*
X79756D01*
X80305Y-814082D01*
X80775Y-814607D01*
G01X85743Y-813872D02*
Y-820172D01*
G01X83941Y-813872D02*
X87545D01*
G01X92043Y-820382D02*
X91886Y-820277D01*
Y-820067D01*
X92043Y-819962D01*
X92200Y-820067D01*
Y-820277D01*
X92043Y-820382D01*
G01X98186Y-821327D02*
X98500Y-819962D01*
G01X104643Y-813872D02*
Y-820172D01*
G01X102841Y-813872D02*
X106445D01*
G01X108985Y-820172D02*
X110943Y-813872D01*
X112901Y-820172D01*
G01X112196Y-817967D02*
X109690D01*
G01X117243Y-820172D02*
X116616Y-820067D01*
X116068Y-819647D01*
X115598Y-819017D01*
X115285Y-818282D01*
X115128Y-817442D01*
Y-816602D01*
X115285Y-815762D01*
X115598Y-815027D01*
X116068Y-814397D01*
X116616Y-813977D01*
X117243Y-813872D01*
X117870Y-813977D01*
X118418Y-814397D01*
X118888Y-815027D01*
X119201Y-815762D01*
X119358Y-816602D01*
Y-817442D01*
X119201Y-818282D01*
X118888Y-819017D01*
X118418Y-819647D01*
X117870Y-820067D01*
X117243Y-820172D01*
G01X123543D02*
Y-817337D01*
X121976Y-813872D01*
G01X125110D02*
X123543Y-817337D01*
G01X128120Y-813872D02*
Y-818387D01*
X128433Y-819332D01*
X129060Y-819962D01*
X129843Y-820172D01*
X130626Y-819962D01*
X131253Y-819332D01*
X131566Y-818387D01*
Y-813872D01*
G01X134185Y-820172D02*
X136143Y-813872D01*
X138101Y-820172D01*
G01X137396Y-817967D02*
X134890D01*
G01X140641Y-820172D02*
Y-813872D01*
X144245Y-820172D01*
Y-813872D01*
G01X18166Y-824397D02*
X17696Y-824082D01*
X17148Y-823872D01*
X16521D01*
X15816Y-824187D01*
X15268Y-824712D01*
X14876Y-825342D01*
X14563Y-826392D01*
X14485Y-827337D01*
X14641Y-828282D01*
X14876Y-828912D01*
X15346Y-829542D01*
X15895Y-829962D01*
X16443Y-830172D01*
X16991D01*
X17540Y-829962D01*
X18010Y-829647D01*
X18401Y-829227D01*
G01X21803Y-823872D02*
X23683D01*
G01X22743D02*
Y-830172D01*
G01X21803D02*
X23683D01*
G01X29043Y-823872D02*
Y-830172D01*
G01X27241Y-823872D02*
X30845D01*
G01X35343Y-830172D02*
Y-827337D01*
X33776Y-823872D01*
G01X36910D02*
X35343Y-827337D01*
G01X46220Y-828912D02*
X46690Y-829647D01*
X47316Y-830067D01*
X48021Y-830172D01*
X48648Y-830067D01*
X49275Y-829542D01*
X49666Y-828912D01*
X49745Y-828282D01*
X49588Y-827547D01*
X49040Y-827022D01*
X48491Y-826812D01*
X47786D01*
G01X48491D02*
X48961Y-826497D01*
X49353Y-825972D01*
X49510Y-825342D01*
X49353Y-824712D01*
X48961Y-824187D01*
X48256Y-823872D01*
X47551Y-823977D01*
X46846Y-824397D01*
G01X52520Y-828912D02*
X52990Y-829647D01*
X53616Y-830067D01*
X54321Y-830172D01*
X54948Y-830067D01*
X55575Y-829542D01*
X55966Y-828912D01*
X56045Y-828282D01*
X55888Y-827547D01*
X55340Y-827022D01*
X54791Y-826812D01*
X54086D01*
G01X54791D02*
X55261Y-826497D01*
X55653Y-825972D01*
X55810Y-825342D01*
X55653Y-824712D01*
X55261Y-824187D01*
X54556Y-823872D01*
X53851Y-823977D01*
X53146Y-824397D01*
G01X58820Y-828912D02*
X59290Y-829647D01*
X59916Y-830067D01*
X60621Y-830172D01*
X61248Y-830067D01*
X61875Y-829542D01*
X62266Y-828912D01*
X62345Y-828282D01*
X62188Y-827547D01*
X61640Y-827022D01*
X61091Y-826812D01*
X60386D01*
G01X61091D02*
X61561Y-826497D01*
X61953Y-825972D01*
X62110Y-825342D01*
X61953Y-824712D01*
X61561Y-824187D01*
X60856Y-823872D01*
X60151Y-823977D01*
X59446Y-824397D01*
G01X66686Y-830172D02*
X66843Y-828807D01*
X67078Y-827652D01*
X67391Y-826602D01*
X67783Y-825447D01*
X68410Y-823872D01*
X65276D01*
G01X72986Y-830172D02*
X73143Y-828807D01*
X73378Y-827652D01*
X73691Y-826602D01*
X74083Y-825447D01*
X74710Y-823872D01*
X71576D01*
G01X79286Y-831327D02*
X79600Y-829962D01*
G01X85743Y-823872D02*
Y-830172D01*
G01X83941Y-823872D02*
X87545D01*
G01X90085Y-830172D02*
X92043Y-823872D01*
X94001Y-830172D01*
G01X93296Y-827967D02*
X90790D01*
G01X97403Y-823872D02*
X99283D01*
G01X98343D02*
Y-830172D01*
G01X97403D02*
X99283D01*
G01X102293Y-823872D02*
X103390Y-830172D01*
X104643Y-823872D01*
X105896Y-830172D01*
X106993Y-823872D01*
G01X108985Y-830172D02*
X110943Y-823872D01*
X112901Y-830172D01*
G01X112196Y-827967D02*
X109690D01*
G01X115441Y-830172D02*
Y-823872D01*
X119045Y-830172D01*
Y-823872D01*
G01X129451Y-832272D02*
X128668Y-831222D01*
X128276Y-830172D01*
Y-825972D01*
X128668Y-824922D01*
X129451Y-823872D01*
G01X140876Y-830172D02*
Y-823872D01*
X142835D01*
X143461Y-824187D01*
X143853Y-824607D01*
X144010Y-825447D01*
X143853Y-826287D01*
X143383Y-826812D01*
X142835Y-827127D01*
X140876D01*
G01X142835D02*
X144010Y-830172D01*
G01X148743Y-830382D02*
X148586Y-830277D01*
Y-830067D01*
X148743Y-829962D01*
X148900Y-830067D01*
Y-830277D01*
X148743Y-830382D01*
G01X155043Y-830172D02*
X154416Y-830067D01*
X153868Y-829647D01*
X153398Y-829017D01*
X153085Y-828282D01*
X152928Y-827442D01*
Y-826602D01*
X153085Y-825762D01*
X153398Y-825027D01*
X153868Y-824397D01*
X154416Y-823977D01*
X155043Y-823872D01*
X155670Y-823977D01*
X156218Y-824397D01*
X156688Y-825027D01*
X157001Y-825762D01*
X157158Y-826602D01*
Y-827442D01*
X157001Y-828282D01*
X156688Y-829017D01*
X156218Y-829647D01*
X155670Y-830067D01*
X155043Y-830172D01*
G01X161343Y-830382D02*
X161186Y-830277D01*
Y-830067D01*
X161343Y-829962D01*
X161500Y-830067D01*
Y-830277D01*
X161343Y-830382D01*
G01X169366Y-824397D02*
X168896Y-824082D01*
X168348Y-823872D01*
X167721D01*
X167016Y-824187D01*
X166468Y-824712D01*
X166076Y-825342D01*
X165763Y-826392D01*
X165685Y-827337D01*
X165841Y-828282D01*
X166076Y-828912D01*
X166546Y-829542D01*
X167095Y-829962D01*
X167643Y-830172D01*
X168191D01*
X168740Y-829962D01*
X169210Y-829647D01*
X169601Y-829227D01*
G01X173943Y-830382D02*
X173786Y-830277D01*
Y-830067D01*
X173943Y-829962D01*
X174100Y-830067D01*
Y-830277D01*
X173943Y-830382D01*
G01X180635Y-832272D02*
X181418Y-831222D01*
X181810Y-830172D01*
Y-825972D01*
X181418Y-824922D01*
X180635Y-823872D01*
G01X38743Y-799472D02*
X36223Y-799055D01*
X34018Y-797389D01*
X32128Y-794889D01*
X30868Y-791972D01*
X30238Y-788639D01*
Y-785305D01*
X30868Y-781972D01*
X32128Y-779055D01*
X34018Y-776556D01*
X36223Y-774889D01*
X38743Y-774472D01*
X41263Y-774889D01*
X43468Y-776556D01*
X45358Y-779055D01*
X46618Y-781972D01*
X47248Y-785305D01*
Y-788639D01*
X46618Y-791972D01*
X45358Y-794889D01*
X43468Y-797389D01*
X41263Y-799055D01*
X38743Y-799472D01*
G01X41263Y-792805D02*
X45043Y-799472D01*
G01X58588Y-782806D02*
Y-794472D01*
X59848Y-797389D01*
X61738Y-799055D01*
X63943Y-799472D01*
X66148Y-799055D01*
X68038Y-797389D01*
X69298Y-794472D01*
G01Y-799472D02*
Y-782806D01*
G01X94813Y-799472D02*
Y-782806D01*
G01Y-785722D02*
X93553Y-784056D01*
X91663Y-783222D01*
X89458Y-782806D01*
X87253Y-783639D01*
X85363Y-785305D01*
X84103Y-787806D01*
X83473Y-791139D01*
X84103Y-794472D01*
X85363Y-796973D01*
X87253Y-798639D01*
X89458Y-799472D01*
X91663Y-799055D01*
X93553Y-797806D01*
X94813Y-796139D01*
G01X108988Y-799472D02*
Y-782806D01*
G01Y-786972D02*
X110248Y-784889D01*
X112138Y-783222D01*
X114658Y-782806D01*
X116863Y-783222D01*
X118753Y-784889D01*
X119698Y-787806D01*
Y-799472D01*
G01X139543Y-774472D02*
Y-799472D01*
G01X135133Y-782806D02*
X143953D01*
G01X170413Y-799472D02*
Y-782806D01*
G01Y-785722D02*
X169153Y-784056D01*
X167263Y-783222D01*
X165058Y-782806D01*
X162853Y-783639D01*
X160963Y-785305D01*
X159703Y-787806D01*
X159073Y-791139D01*
X159703Y-794472D01*
X160963Y-796973D01*
X162853Y-798639D01*
X165058Y-799472D01*
X167263Y-799055D01*
X169153Y-797806D01*
X170413Y-796139D01*
G01X14641Y-810172D02*
Y-803872D01*
X18245Y-810172D01*
Y-803872D01*
G01X22743Y-810172D02*
X22116Y-810067D01*
X21568Y-809647D01*
X21098Y-809017D01*
X20785Y-808282D01*
X20628Y-807442D01*
Y-806602D01*
X20785Y-805762D01*
X21098Y-805027D01*
X21568Y-804397D01*
X22116Y-803977D01*
X22743Y-803872D01*
X23370Y-803977D01*
X23918Y-804397D01*
X24388Y-805027D01*
X24701Y-805762D01*
X24858Y-806602D01*
Y-807442D01*
X24701Y-808282D01*
X24388Y-809017D01*
X23918Y-809647D01*
X23370Y-810067D01*
X22743Y-810172D01*
G01X29043Y-810382D02*
X28886Y-810277D01*
Y-810067D01*
X29043Y-809962D01*
X29200Y-810067D01*
Y-810277D01*
X29043Y-810382D01*
G01X33855Y-804922D02*
X34325Y-804292D01*
X34873Y-803977D01*
X35500Y-803872D01*
X36283Y-804082D01*
X36831Y-804607D01*
X36988Y-805237D01*
X36910Y-805867D01*
X36596Y-806392D01*
X35030Y-807442D01*
X34325Y-808177D01*
X33855Y-809227D01*
X33698Y-810172D01*
X36988D01*
G01X41643D02*
Y-803872D01*
X40703Y-805132D01*
G01Y-810172D02*
X42583D01*
G01X47943D02*
Y-803872D01*
X47003Y-805132D01*
G01Y-810172D02*
X48883D01*
G01X54086Y-811327D02*
X54400Y-809962D01*
G01X58193Y-803872D02*
X59290Y-810172D01*
X60543Y-803872D01*
X61796Y-810172D01*
X62893Y-803872D01*
G01X68410Y-810172D02*
X65276D01*
Y-803872D01*
X68410D01*
G01X67156Y-806917D02*
X65276D01*
G01X71341Y-810172D02*
Y-803872D01*
X74945Y-810172D01*
Y-803872D01*
G01X77798Y-810172D02*
Y-803872D01*
G01X81088D02*
Y-810172D01*
G01Y-807022D02*
X77798D01*
G01X84020Y-803872D02*
Y-808387D01*
X84333Y-809332D01*
X84960Y-809962D01*
X85743Y-810172D01*
X86526Y-809962D01*
X87153Y-809332D01*
X87466Y-808387D01*
Y-803872D01*
G01X90085Y-810172D02*
X92043Y-803872D01*
X94001Y-810172D01*
G01X93296Y-807967D02*
X90790D01*
G01X103155Y-804922D02*
X103625Y-804292D01*
X104173Y-803977D01*
X104800Y-803872D01*
X105583Y-804082D01*
X106131Y-804607D01*
X106288Y-805237D01*
X106210Y-805867D01*
X105896Y-806392D01*
X104330Y-807442D01*
X103625Y-808177D01*
X103155Y-809227D01*
X102998Y-810172D01*
X106288D01*
G01X109141D02*
Y-803872D01*
X112745Y-810172D01*
Y-803872D01*
G01X115520Y-810172D02*
Y-803872D01*
X117086D01*
X117713Y-804187D01*
X118183Y-804607D01*
X118575Y-805237D01*
X118888Y-805972D01*
X118966Y-807022D01*
X118888Y-808072D01*
X118575Y-808807D01*
X118183Y-809437D01*
X117713Y-809857D01*
X117086Y-810172D01*
X115520D01*
G01X128276D02*
Y-803872D01*
X130235D01*
X130861Y-804187D01*
X131253Y-804607D01*
X131410Y-805447D01*
X131253Y-806287D01*
X130783Y-806812D01*
X130235Y-807127D01*
X128276D01*
G01X130235D02*
X131410Y-810172D01*
G01X134420D02*
Y-803872D01*
X135986D01*
X136613Y-804187D01*
X137083Y-804607D01*
X137475Y-805237D01*
X137788Y-805972D01*
X137866Y-807022D01*
X137788Y-808072D01*
X137475Y-808807D01*
X137083Y-809437D01*
X136613Y-809857D01*
X135986Y-810172D01*
X134420D01*
G01X142443Y-810382D02*
X142286Y-810277D01*
Y-810067D01*
X142443Y-809962D01*
X142600Y-810067D01*
Y-810277D01*
X142443Y-810382D01*
G01X210093Y-779172D02*
Y-787172D01*
X214093D01*
G01X221893D02*
Y-781839D01*
G01Y-782772D02*
X221493Y-782239D01*
X220893Y-781972D01*
X220193Y-781839D01*
X219493Y-782105D01*
X218893Y-782639D01*
X218493Y-783439D01*
X218293Y-784505D01*
X218493Y-785572D01*
X218893Y-786372D01*
X219493Y-786905D01*
X220193Y-787172D01*
X220893Y-787039D01*
X221493Y-786639D01*
X221893Y-786106D01*
G01X225993Y-789572D02*
X226593Y-789839D01*
X227393Y-789572D01*
X227893Y-789039D01*
X228293Y-788372D01*
X228893Y-786239D01*
X230193Y-781839D01*
G01X226993D02*
X228893Y-786239D01*
G01X234593Y-783572D02*
X237793D01*
X237493Y-782639D01*
X236993Y-782105D01*
X236293Y-781839D01*
X235593Y-781972D01*
X234993Y-782372D01*
X234593Y-783305D01*
X234393Y-784106D01*
Y-784905D01*
X234593Y-785705D01*
X235093Y-786505D01*
X235693Y-787039D01*
X236393Y-787172D01*
X237093Y-786905D01*
X237793Y-786106D01*
G01X242693Y-787172D02*
Y-781839D01*
G01Y-782905D02*
X243193Y-782372D01*
X243693Y-781972D01*
X244393Y-781839D01*
X244893Y-781972D01*
X245493Y-782372D01*
G01X229193Y-829172D02*
X232993D01*
X229193Y-837172D01*
X232993D01*
G01X239093Y-831839D02*
Y-837172D01*
G01Y-829705D02*
X238893Y-829572D01*
Y-829305D01*
X239093Y-829172D01*
X239293Y-829305D01*
Y-829572D01*
X239093Y-829705D01*
G01X245793Y-834505D02*
X248393D01*
G01X253093Y-837172D02*
Y-829172D01*
X255493D01*
X256293Y-829572D01*
X256893Y-830505D01*
X257093Y-831572D01*
X256893Y-832639D01*
X256393Y-833439D01*
X255493Y-833839D01*
X253093D01*
G01X263093Y-831839D02*
Y-837172D01*
G01Y-829705D02*
X262893Y-829572D01*
Y-829305D01*
X263093Y-829172D01*
X263293Y-829305D01*
Y-829572D01*
X263093Y-829705D01*
G01X269393Y-837172D02*
Y-831839D01*
G01Y-833172D02*
X269793Y-832505D01*
X270393Y-831972D01*
X271193Y-831839D01*
X271893Y-831972D01*
X272493Y-832505D01*
X272793Y-833439D01*
Y-837172D01*
G01X277693Y-839172D02*
X278393Y-839705D01*
X279193Y-839839D01*
X279893Y-839705D01*
X280493Y-839039D01*
X280893Y-838105D01*
Y-831839D01*
G01Y-832905D02*
X280493Y-832372D01*
X279893Y-831972D01*
X279193Y-831839D01*
X278393Y-832105D01*
X277893Y-832639D01*
X277493Y-833572D01*
X277293Y-834505D01*
X277393Y-835305D01*
X277793Y-836239D01*
X278393Y-836905D01*
X279193Y-837172D01*
X279793Y-837039D01*
X280493Y-836505D01*
X280893Y-835972D01*
G01X221593Y-812172D02*
Y-804172D01*
X223993D01*
X224793Y-804572D01*
X225393Y-805505D01*
X225593Y-806572D01*
X225393Y-807639D01*
X224893Y-808439D01*
X223993Y-808839D01*
X221593D01*
G01X229093Y-812172D02*
X231593Y-804172D01*
X234093Y-812172D01*
G01X233193Y-809372D02*
X229993D01*
G01X237493Y-811106D02*
X238293Y-811772D01*
X239193Y-812172D01*
X239993D01*
X240793Y-811772D01*
X241393Y-811106D01*
X241693Y-810172D01*
X241493Y-809239D01*
X240993Y-808439D01*
X240093Y-807905D01*
X238893Y-807639D01*
X238193Y-807105D01*
X237893Y-806172D01*
X238093Y-805239D01*
X238593Y-804572D01*
X239293Y-804172D01*
X239993D01*
X240693Y-804439D01*
X241293Y-805105D01*
G01X247593Y-804172D02*
Y-812172D01*
G01X245293Y-804172D02*
X249893D01*
G01X254293Y-809505D02*
X256893D01*
G01X264393Y-807905D02*
X264793Y-807505D01*
X265093Y-806839D01*
X265293Y-805905D01*
X265093Y-805105D01*
X264693Y-804572D01*
X263993Y-804172D01*
X261293D01*
Y-812172D01*
X264593D01*
X265293Y-811639D01*
X265693Y-810839D01*
X265893Y-809905D01*
X265693Y-808972D01*
X265093Y-808172D01*
X264393Y-807905D01*
X261293D01*
G01X271593Y-812172D02*
X270793Y-812039D01*
X270093Y-811505D01*
X269493Y-810705D01*
X269093Y-809772D01*
X268893Y-808705D01*
Y-807639D01*
X269093Y-806572D01*
X269493Y-805639D01*
X270093Y-804839D01*
X270793Y-804305D01*
X271593Y-804172D01*
X272393Y-804305D01*
X273093Y-804839D01*
X273693Y-805639D01*
X274093Y-806572D01*
X274293Y-807639D01*
Y-808705D01*
X274093Y-809772D01*
X273693Y-810705D01*
X273093Y-811505D01*
X272393Y-812039D01*
X271593Y-812172D01*
G01X279593Y-804172D02*
Y-812172D01*
G01X277293Y-804172D02*
X281893D01*
G01X336693Y-830505D02*
X337293Y-829705D01*
X337993Y-829305D01*
X338793Y-829172D01*
X339793Y-829439D01*
X340493Y-830105D01*
X340693Y-830905D01*
X340593Y-831706D01*
X340193Y-832372D01*
X338193Y-833705D01*
X337293Y-834639D01*
X336693Y-835972D01*
X336493Y-837172D01*
X340693D01*
G01X346593Y-829172D02*
X345793Y-829439D01*
X345193Y-830105D01*
X344793Y-830905D01*
X344493Y-831972D01*
X344393Y-833172D01*
X344493Y-834372D01*
X344793Y-835439D01*
X345193Y-836239D01*
X345793Y-836905D01*
X346593Y-837172D01*
X347393Y-836905D01*
X347993Y-836239D01*
X348393Y-835439D01*
X348693Y-834372D01*
X348793Y-833172D01*
X348693Y-831972D01*
X348393Y-830905D01*
X347993Y-830105D01*
X347393Y-829439D01*
X346593Y-829172D01*
G01X352693Y-830505D02*
X353293Y-829705D01*
X353993Y-829305D01*
X354793Y-829172D01*
X355793Y-829439D01*
X356493Y-830105D01*
X356693Y-830905D01*
X356593Y-831706D01*
X356193Y-832372D01*
X354193Y-833705D01*
X353293Y-834639D01*
X352693Y-835972D01*
X352493Y-837172D01*
X356693D01*
G01X360693Y-830505D02*
X361293Y-829705D01*
X361993Y-829305D01*
X362793Y-829172D01*
X363793Y-829439D01*
X364493Y-830105D01*
X364693Y-830905D01*
X364593Y-831706D01*
X364193Y-832372D01*
X362193Y-833705D01*
X361293Y-834639D01*
X360693Y-835972D01*
X360493Y-837172D01*
X364693D01*
G01X368793Y-837439D02*
X372393Y-829172D01*
G01X378593Y-837172D02*
Y-829172D01*
X377393Y-830772D01*
G01Y-837172D02*
X379793D01*
G01X384693Y-830505D02*
X385293Y-829705D01*
X385993Y-829305D01*
X386793Y-829172D01*
X387793Y-829439D01*
X388493Y-830105D01*
X388693Y-830905D01*
X388593Y-831706D01*
X388193Y-832372D01*
X386193Y-833705D01*
X385293Y-834639D01*
X384693Y-835972D01*
X384493Y-837172D01*
X388693D01*
G01X392793Y-837439D02*
X396393Y-829172D01*
G01X402593D02*
X401793Y-829439D01*
X401193Y-830105D01*
X400793Y-830905D01*
X400493Y-831972D01*
X400393Y-833172D01*
X400493Y-834372D01*
X400793Y-835439D01*
X401193Y-836239D01*
X401793Y-836905D01*
X402593Y-837172D01*
X403393Y-836905D01*
X403993Y-836239D01*
X404393Y-835439D01*
X404693Y-834372D01*
X404793Y-833172D01*
X404693Y-831972D01*
X404393Y-830905D01*
X403993Y-830105D01*
X403393Y-829439D01*
X402593Y-829172D01*
G01X408693Y-830505D02*
X409293Y-829705D01*
X409993Y-829305D01*
X410793Y-829172D01*
X411793Y-829439D01*
X412493Y-830105D01*
X412693Y-830905D01*
X412593Y-831706D01*
X412193Y-832372D01*
X410193Y-833705D01*
X409293Y-834639D01*
X408693Y-835972D01*
X408493Y-837172D01*
X412693D01*
G01X336393Y-814672D02*
Y-806672D01*
X338393D01*
X339193Y-807072D01*
X339793Y-807605D01*
X340293Y-808405D01*
X340693Y-809339D01*
X340793Y-810672D01*
X340693Y-812005D01*
X340293Y-812939D01*
X339793Y-813739D01*
X339193Y-814272D01*
X338393Y-814672D01*
X336393D01*
G01X344093D02*
X346593Y-806672D01*
X349093Y-814672D01*
G01X348193Y-811872D02*
X344993D01*
G01X354593Y-806672D02*
X353793Y-806939D01*
X353193Y-807605D01*
X352793Y-808405D01*
X352493Y-809472D01*
X352393Y-810672D01*
X352493Y-811872D01*
X352793Y-812939D01*
X353193Y-813739D01*
X353793Y-814405D01*
X354593Y-814672D01*
X355393Y-814405D01*
X355993Y-813739D01*
X356393Y-812939D01*
X356693Y-811872D01*
X356793Y-810672D01*
X356693Y-809472D01*
X356393Y-808405D01*
X355993Y-807605D01*
X355393Y-806939D01*
X354593Y-806672D01*
G01X360693Y-814672D02*
Y-806672D01*
X364493D01*
G01X363093Y-810539D02*
X360693D01*
G01X370593Y-806672D02*
X369793Y-806939D01*
X369193Y-807605D01*
X368793Y-808405D01*
X368493Y-809472D01*
X368393Y-810672D01*
X368493Y-811872D01*
X368793Y-812939D01*
X369193Y-813739D01*
X369793Y-814405D01*
X370593Y-814672D01*
X371393Y-814405D01*
X371993Y-813739D01*
X372393Y-812939D01*
X372693Y-811872D01*
X372793Y-810672D01*
X372693Y-809472D01*
X372393Y-808405D01*
X371993Y-807605D01*
X371393Y-806939D01*
X370593Y-806672D01*
G01X378593D02*
Y-814672D01*
G01X376293Y-806672D02*
X380893D01*
G01X384593Y-814672D02*
Y-806672D01*
X386993D01*
X387793Y-807072D01*
X388393Y-808005D01*
X388593Y-809072D01*
X388393Y-810139D01*
X387893Y-810939D01*
X386993Y-811339D01*
X384593D01*
G01X395393Y-810405D02*
X395793Y-810005D01*
X396093Y-809339D01*
X396293Y-808405D01*
X396093Y-807605D01*
X395693Y-807072D01*
X394993Y-806672D01*
X392293D01*
Y-814672D01*
X395593D01*
X396293Y-814139D01*
X396693Y-813339D01*
X396893Y-812405D01*
X396693Y-811472D01*
X396093Y-810672D01*
X395393Y-810405D01*
X392293D01*
G01X400093Y-814672D02*
X402593Y-806672D01*
X405093Y-814672D01*
G01X404193Y-811872D02*
X400993D01*
G01X408693Y-814672D02*
Y-806672D01*
X412493D01*
G01X411093Y-810539D02*
X408693D01*
G01X418593Y-806672D02*
X417793Y-806939D01*
X417193Y-807605D01*
X416793Y-808405D01*
X416493Y-809472D01*
X416393Y-810672D01*
X416493Y-811872D01*
X416793Y-812939D01*
X417193Y-813739D01*
X417793Y-814405D01*
X418593Y-814672D01*
X419393Y-814405D01*
X419993Y-813739D01*
X420393Y-812939D01*
X420693Y-811872D01*
X420793Y-810672D01*
X420693Y-809472D01*
X420393Y-808405D01*
X419993Y-807605D01*
X419393Y-806939D01*
X418593Y-806672D01*
G01X356693Y-787172D02*
Y-779172D01*
X360493D01*
G01X359093Y-783039D02*
X356693D01*
G01X366593Y-779172D02*
X365793Y-779439D01*
X365193Y-780105D01*
X364793Y-780905D01*
X364493Y-781972D01*
X364393Y-783172D01*
X364493Y-784372D01*
X364793Y-785439D01*
X365193Y-786239D01*
X365793Y-786905D01*
X366593Y-787172D01*
X367393Y-786905D01*
X367993Y-786239D01*
X368393Y-785439D01*
X368693Y-784372D01*
X368793Y-783172D01*
X368693Y-781972D01*
X368393Y-780905D01*
X367993Y-780105D01*
X367393Y-779439D01*
X366593Y-779172D01*
G01X374593D02*
Y-787172D01*
G01X372293Y-779172D02*
X376893D01*
G01X379593Y-789839D02*
X385593D01*
G01X388593Y-787172D02*
Y-779172D01*
X390993D01*
X391793Y-779572D01*
X392393Y-780505D01*
X392593Y-781572D01*
X392393Y-782639D01*
X391893Y-783439D01*
X390993Y-783839D01*
X388593D01*
G01X396393Y-787172D02*
Y-779172D01*
X398393D01*
X399193Y-779572D01*
X399793Y-780105D01*
X400293Y-780905D01*
X400693Y-781839D01*
X400793Y-783172D01*
X400693Y-784505D01*
X400293Y-785439D01*
X399793Y-786239D01*
X399193Y-786772D01*
X398393Y-787172D01*
X396393D01*
G01X407393Y-782905D02*
X407793Y-782505D01*
X408093Y-781839D01*
X408293Y-780905D01*
X408093Y-780105D01*
X407693Y-779572D01*
X406993Y-779172D01*
X404293D01*
Y-787172D01*
X407593D01*
X408293Y-786639D01*
X408693Y-785839D01*
X408893Y-784905D01*
X408693Y-783972D01*
X408093Y-783172D01*
X407393Y-782905D01*
X404293D01*
G01X411593Y-789839D02*
X417593D01*
G01X424793Y-779839D02*
X424193Y-779439D01*
X423493Y-779172D01*
X422693D01*
X421793Y-779572D01*
X421093Y-780239D01*
X420593Y-781039D01*
X420193Y-782372D01*
X420093Y-783572D01*
X420293Y-784772D01*
X420593Y-785572D01*
X421193Y-786372D01*
X421893Y-786905D01*
X422593Y-787172D01*
X423293D01*
X423993Y-786905D01*
X424593Y-786505D01*
X425093Y-785972D01*
G01X430593Y-787172D02*
X429793Y-787039D01*
X429093Y-786505D01*
X428493Y-785705D01*
X428093Y-784772D01*
X427893Y-783705D01*
Y-782639D01*
X428093Y-781572D01*
X428493Y-780639D01*
X429093Y-779839D01*
X429793Y-779305D01*
X430593Y-779172D01*
X431393Y-779305D01*
X432093Y-779839D01*
X432693Y-780639D01*
X433093Y-781572D01*
X433293Y-782639D01*
Y-783705D01*
X433093Y-784772D01*
X432693Y-785705D01*
X432093Y-786505D01*
X431393Y-787039D01*
X430593Y-787172D01*
G01X436293D02*
Y-779172D01*
X440893Y-787172D01*
Y-779172D01*
G01X444093D02*
X446593Y-787172D01*
X449093Y-779172D01*
G01X456593Y-787172D02*
X452593D01*
Y-779172D01*
X456593D01*
G01X454993Y-783039D02*
X452593D01*
G01X460593Y-787172D02*
Y-779172D01*
X463093D01*
X463893Y-779572D01*
X464393Y-780105D01*
X464593Y-781172D01*
X464393Y-782239D01*
X463793Y-782905D01*
X463093Y-783305D01*
X460593D01*
G01X463093D02*
X464593Y-787172D01*
G01X470593Y-779172D02*
Y-787172D01*
G01X468293Y-779172D02*
X472893D01*
G01X480593Y-787172D02*
X476593D01*
Y-779172D01*
X480593D01*
G01X478993Y-783039D02*
X476593D01*
G01X484593Y-787172D02*
Y-779172D01*
X487093D01*
X487893Y-779572D01*
X488393Y-780105D01*
X488593Y-781172D01*
X488393Y-782239D01*
X487793Y-782905D01*
X487093Y-783305D01*
X484593D01*
G01X487093D02*
X488593Y-787172D01*
G01X425093Y-840172D02*
Y-832172D01*
X423893Y-833772D01*
G01Y-840172D02*
X426293D01*
G01X431193Y-836839D02*
X431893Y-835905D01*
X432493Y-835372D01*
X433293Y-835105D01*
X433993Y-835372D01*
X434493Y-835905D01*
X434893Y-836705D01*
X434993Y-837639D01*
X434893Y-838439D01*
X434493Y-839239D01*
X433893Y-839905D01*
X433193Y-840172D01*
X432393Y-839905D01*
X431693Y-839106D01*
X431293Y-837905D01*
X431193Y-836572D01*
X431393Y-834839D01*
X431693Y-833905D01*
X432193Y-832972D01*
X432893Y-832305D01*
X433593Y-832172D01*
X434293Y-832439D01*
X434793Y-833105D01*
G01X441093Y-840439D02*
X440893Y-840305D01*
Y-840039D01*
X441093Y-839905D01*
X441293Y-840039D01*
Y-840305D01*
X441093Y-840439D01*
G01X447193Y-836839D02*
X447893Y-835905D01*
X448493Y-835372D01*
X449293Y-835105D01*
X449993Y-835372D01*
X450493Y-835905D01*
X450893Y-836705D01*
X450993Y-837639D01*
X450893Y-838439D01*
X450493Y-839239D01*
X449893Y-839905D01*
X449193Y-840172D01*
X448393Y-839905D01*
X447693Y-839106D01*
X447293Y-837905D01*
X447193Y-836572D01*
X447393Y-834839D01*
X447693Y-833905D01*
X448193Y-832972D01*
X448893Y-832305D01*
X449593Y-832172D01*
X450293Y-832439D01*
X450793Y-833105D01*
G01X470093Y-840172D02*
Y-832172D01*
X468893Y-833772D01*
G01Y-840172D02*
X471293D01*
G01X477893D02*
X478093Y-838439D01*
X478393Y-836972D01*
X478793Y-835639D01*
X479293Y-834172D01*
X480093Y-832172D01*
X476093D01*
G01X486093Y-840439D02*
X485893Y-840305D01*
Y-840039D01*
X486093Y-839905D01*
X486293Y-840039D01*
Y-840305D01*
X486093Y-840439D01*
G01X492193Y-833505D02*
X492793Y-832705D01*
X493493Y-832305D01*
X494293Y-832172D01*
X495293Y-832439D01*
X495993Y-833105D01*
X496193Y-833905D01*
X496093Y-834706D01*
X495693Y-835372D01*
X493693Y-836705D01*
X492793Y-837639D01*
X492193Y-838972D01*
X491993Y-840172D01*
X496193D01*
G01X490193Y-815172D02*
Y-807172D01*
X493993D01*
G01X492593Y-811039D02*
X490193D01*
G54D38*
X819925Y288000D03*
X822484D03*
X825043D03*
X827602D03*
X830161D03*
X832720D03*
X835280D03*
Y311000D03*
X832720D03*
X830161D03*
X827602D03*
X825043D03*
X822484D03*
X819925D03*
X837839Y288000D03*
X840398D03*
X842957D03*
X845516D03*
X848075D03*
Y311000D03*
X845516D03*
X842957D03*
X840398D03*
X837839D03*
G54D47*
X1049760Y111500D03*
X1057240D03*
X1091240Y135000D03*
X1083760D03*
X1120260Y214500D03*
X1127740D03*
X1146760Y177000D03*
X1154240D03*
G54D29*
X193819Y477204D03*
X223819D03*
X351299D03*
X381299D03*
X508780D03*
X538780D03*
X666261D03*
X696261D03*
G54D39*
X831059Y349740D03*
X825941D03*
Y342260D03*
X828500D03*
X831059D03*
X905941Y309260D03*
X908500D03*
X911059D03*
Y316740D03*
X905941D03*
G54D48*
X1077500Y100563D03*
X1081240Y108437D03*
X1073760D03*
X1088000Y156937D03*
X1084260Y149063D03*
X1091740D03*
G54D49*
X1093343Y364043D03*
X1092000Y349800D03*
Y344000D03*
X1093343Y369843D03*
X1091000Y397400D03*
Y391600D03*
X1093343Y417343D03*
Y411543D03*
M02*
